(kicad_pcb
	(version 20260206)
	(generator "pcbnew")
	(generator_version "10.0")
	(general
		(thickness 1.6)
		(legacy_teardrops no)
	)
	(paper "A4")
	(title_block
		(title "01162023_DA0F0TEBIF0_F0T_Expander_BD_F_brd_V02_OCP.brd")
		(comment 1 "Grand Teton / footprint 1907 of 9728 (J14), pads 78-142 of 142")
	)
	(layers
		(0 "F.Cu" signal "TOP")
		(4 "In1.Cu" signal "GND")
		(6 "In2.Cu" signal "VCC")
		(8 "In3.Cu" signal "VCC1")
		(10 "In4.Cu" signal "GND1")
		(12 "In5.Cu" signal "IN1")
		(14 "In6.Cu" signal "GND2")
		(16 "In7.Cu" signal "IN2")
		(18 "In8.Cu" signal "GND3")
		(20 "In9.Cu" signal "IN3")
		(22 "In10.Cu" signal "GND4")
		(24 "In11.Cu" signal "IN4")
		(26 "In12.Cu" signal "GND5")
		(28 "In13.Cu" signal "IN5")
		(30 "In14.Cu" signal "GND6")
		(32 "In15.Cu" signal "IN6")
		(34 "In16.Cu" signal "GND7")
		(2 "B.Cu" signal "BOTTOM")
		(9 "F.Adhes" user "F.Adhesive")
		(11 "B.Adhes" user "B.Adhesive")
		(13 "F.Paste" user "Package Geometry/Pastemask Top")
		(15 "B.Paste" user "Package Geometry/Pastemask Bottom")
		(5 "F.SilkS" user "Ref Des/Silkscreen Top")
		(7 "B.SilkS" user "Ref Des/Silkscreen Bottom")
		(1 "F.Mask" user "Board Geometry/Soldermask Top")
		(3 "B.Mask" user "Board Geometry/Soldermask Bottom")
		(17 "Dwgs.User" user "User.Drawings")
		(19 "Cmts.User" user "User.Comments")
		(21 "Eco1.User" user "User.Eco1")
		(23 "Eco2.User" user "User.Eco2")
		(25 "Edge.Cuts" user "Board Geometry/Outline")
		(27 "Margin" user)
		(31 "F.CrtYd" user "Package Geometry/Place Bound Top")
		(29 "B.CrtYd" user "Package Geometry/Place Bound Bottom")
		(35 "F.Fab" user "Ref Des/Assembly Top")
		(33 "B.Fab" user "Ref Des/Assembly Bottom")
	)
	(footprint ""
		(layer "F.Cu")
		(at 375.489978 -412.090108)
		(property "Reference" "J14"
			(at 26.41727 7.51459 90)
			(unlocked yes)
			(layer "F.SilkS")
			(effects
				(font
					(size 2.032 1.524)
					(thickness 0.1524)
				)
				(justify left)
			)
		)
		(property "Value" ""
			(at 0 0 0)
			(layer "F.Fab")
			(effects
				(font
					(size 1.27 1.27)
				)
			)
		)
		(duplicate_pad_numbers_are_jumpers no)
		(pad "N2_3" thru_hole circle
			(at 4.400042 27.29992 180)
			(size 0.906272 0.906272)
			(drill 0.499872)
			(layers "*.Cu" "*.Mask")
			(remove_unused_layers no)
			(net "GND")
			(clearance 0.0508)
			(thermal_gap 0.0508)
		)
		(pad "N2_5" thru_hole circle
			(at 8.800084 27.29992 180)
			(size 0.906272 0.906272)
			(drill 0.499872)
			(layers "*.Cu" "*.Mask")
			(remove_unused_layers no)
			(net "GND")
			(clearance 0.0508)
			(thermal_gap 0.0508)
		)
		(pad "N2_7" thru_hole circle
			(at 13.199872 27.29992 180)
			(size 0.906272 0.906272)
			(drill 0.499872)
			(layers "*.Cu" "*.Mask")
			(remove_unused_layers no)
			(net "GND")
			(clearance 0.0508)
			(thermal_gap 0.0508)
		)
		(pad "N2_9" thru_hole circle
			(at 17.599914 27.29992 180)
			(size 0.906272 0.906272)
			(drill 0.499872)
			(layers "*.Cu" "*.Mask")
			(remove_unused_layers no)
			(net "GND")
			(clearance 0.0508)
			(thermal_gap 0.0508)
		)
		(pad "N10" thru_hole circle
			(at 19.800062 27.500072 180)
			(size 0.71628 0.71628)
			(drill 0.30988)
			(layers "*.Cu" "*.Mask")
			(remove_unused_layers no)
			(net "Net_8861")
			(clearance 0.0508)
			(thermal_gap 0.0508)
		)
		(pad "O9" thru_hole circle
			(at 17.599914 28.599892 180)
			(size 0.71628 0.71628)
			(drill 0.30988)
			(layers "*.Cu" "*.Mask")
			(remove_unused_layers no)
			(net "Net_8859")
			(clearance 0.0508)
			(thermal_gap 0.0508)
		)
		(pad "O10" thru_hole circle
			(at 19.800062 28.800044 180)
			(size 0.71628 0.71628)
			(drill 0.30988)
			(layers "*.Cu" "*.Mask")
			(remove_unused_layers no)
			(net "Net_8860")
			(clearance 0.0508)
			(thermal_gap 0.0508)
		)
		(pad "P2" thru_hole circle
			(at 2.199894 30.100016 180)
			(size 0.906272 0.906272)
			(drill 0.499872)
			(layers "*.Cu" "*.Mask")
			(remove_unused_layers no)
			(net "GND")
			(clearance 0.0508)
			(thermal_gap 0.0508)
		)
		(pad "P4" thru_hole circle
			(at 6.599936 30.100016 180)
			(size 0.906272 0.906272)
			(drill 0.499872)
			(layers "*.Cu" "*.Mask")
			(remove_unused_layers no)
			(net "GND")
			(clearance 0.0508)
			(thermal_gap 0.0508)
		)
		(pad "P6" thru_hole circle
			(at 10.999978 30.100016 180)
			(size 0.906272 0.906272)
			(drill 0.499872)
			(layers "*.Cu" "*.Mask")
			(remove_unused_layers no)
			(net "GND")
			(clearance 0.0508)
			(thermal_gap 0.0508)
		)
		(pad "P8" thru_hole circle
			(at 15.40002 30.100016 180)
			(size 0.906272 0.906272)
			(drill 0.499872)
			(layers "*.Cu" "*.Mask")
			(remove_unused_layers no)
			(net "GND")
			(clearance 0.0508)
			(thermal_gap 0.0508)
		)
		(pad "P9" thru_hole circle
			(at 17.599914 29.900118 180)
			(size 0.71628 0.71628)
			(drill 0.30988)
			(layers "*.Cu" "*.Mask")
			(remove_unused_layers no)
			(net "Net_8858")
			(clearance 0.0508)
			(thermal_gap 0.0508)
		)
		(pad "P10" thru_hole circle
			(at 19.800062 30.100016 180)
			(size 0.906272 0.906272)
			(drill 0.499872)
			(layers "*.Cu" "*.Mask")
			(remove_unused_layers no)
			(net "GND")
			(clearance 0.0508)
			(thermal_gap 0.0508)
		)
		(pad "Q1" thru_hole circle
			(at 0 31.20009 180)
			(size 0.906272 0.906272)
			(drill 0.499872)
			(layers "*.Cu" "*.Mask")
			(remove_unused_layers no)
			(net "GND")
			(clearance 0.0508)
			(thermal_gap 0.0508)
		)
		(pad "Q3" thru_hole circle
			(at 4.400042 31.20009 180)
			(size 0.906272 0.906272)
			(drill 0.499872)
			(layers "*.Cu" "*.Mask")
			(remove_unused_layers no)
			(net "GND")
			(clearance 0.0508)
			(thermal_gap 0.0508)
		)
		(pad "Q5" thru_hole circle
			(at 8.800084 31.20009 180)
			(size 0.906272 0.906272)
			(drill 0.499872)
			(layers "*.Cu" "*.Mask")
			(remove_unused_layers no)
			(net "GND")
			(clearance 0.0508)
			(thermal_gap 0.0508)
		)
		(pad "Q7" thru_hole circle
			(at 13.199872 31.20009 180)
			(size 0.906272 0.906272)
			(drill 0.499872)
			(layers "*.Cu" "*.Mask")
			(remove_unused_layers no)
			(net "GND")
			(clearance 0.0508)
			(thermal_gap 0.0508)
		)
		(pad "Q9" thru_hole circle
			(at 17.599914 31.20009 180)
			(size 0.906272 0.906272)
			(drill 0.499872)
			(layers "*.Cu" "*.Mask")
			(remove_unused_layers no)
			(net "GND")
			(clearance 0.0508)
			(thermal_gap 0.0508)
		)
		(pad "Q10" thru_hole circle
			(at 19.800062 31.399988 180)
			(size 0.71628 0.71628)
			(drill 0.30988)
			(layers "*.Cu" "*.Mask")
			(remove_unused_layers no)
			(net "Net_8857")
			(clearance 0.0508)
			(thermal_gap 0.0508)
		)
		(pad "R9" thru_hole circle
			(at 17.599914 32.500062 180)
			(size 0.71628 0.71628)
			(drill 0.30988)
			(layers "*.Cu" "*.Mask")
			(remove_unused_layers no)
			(net "Net_8855")
			(clearance 0.0508)
			(thermal_gap 0.0508)
		)
		(pad "R10" thru_hole circle
			(at 19.800062 32.69996 180)
			(size 0.71628 0.71628)
			(drill 0.30988)
			(layers "*.Cu" "*.Mask")
			(remove_unused_layers no)
			(net "Net_8856")
			(clearance 0.0508)
			(thermal_gap 0.0508)
		)
		(pad "S2" thru_hole circle
			(at 2.199894 33.999932 180)
			(size 0.906272 0.906272)
			(drill 0.499872)
			(layers "*.Cu" "*.Mask")
			(remove_unused_layers no)
			(net "GND")
			(clearance 0.0508)
			(thermal_gap 0.0508)
		)
		(pad "S4" thru_hole circle
			(at 6.599936 33.999932 180)
			(size 0.906272 0.906272)
			(drill 0.499872)
			(layers "*.Cu" "*.Mask")
			(remove_unused_layers no)
			(net "GND")
			(clearance 0.0508)
			(thermal_gap 0.0508)
		)
		(pad "S6" thru_hole circle
			(at 10.999978 33.999932 180)
			(size 0.906272 0.906272)
			(drill 0.499872)
			(layers "*.Cu" "*.Mask")
			(remove_unused_layers no)
			(net "GND")
			(clearance 0.0508)
			(thermal_gap 0.0508)
		)
		(pad "S8" thru_hole circle
			(at 15.40002 33.999932 180)
			(size 0.906272 0.906272)
			(drill 0.499872)
			(layers "*.Cu" "*.Mask")
			(remove_unused_layers no)
			(net "GND")
			(clearance 0.0508)
			(thermal_gap 0.0508)
		)
		(pad "S9" thru_hole circle
			(at 17.599914 33.800034 180)
			(size 0.71628 0.71628)
			(drill 0.30988)
			(layers "*.Cu" "*.Mask")
			(remove_unused_layers no)
			(net "Net_8854")
			(clearance 0.0508)
			(thermal_gap 0.0508)
		)
		(pad "S10" thru_hole circle
			(at 19.800062 33.999932 180)
			(size 0.906272 0.906272)
			(drill 0.499872)
			(layers "*.Cu" "*.Mask")
			(remove_unused_layers no)
			(net "GND")
			(clearance 0.0508)
			(thermal_gap 0.0508)
		)
		(pad "T1" thru_hole circle
			(at 0 35.100006 180)
			(size 0.906272 0.906272)
			(drill 0.499872)
			(layers "*.Cu" "*.Mask")
			(remove_unused_layers no)
			(net "GND")
			(clearance 0.0508)
			(thermal_gap 0.0508)
		)
		(pad "T3" thru_hole circle
			(at 4.400042 35.100006 180)
			(size 0.906272 0.906272)
			(drill 0.499872)
			(layers "*.Cu" "*.Mask")
			(remove_unused_layers no)
			(net "GND")
			(clearance 0.0508)
			(thermal_gap 0.0508)
		)
		(pad "T5" thru_hole circle
			(at 8.800084 35.100006 180)
			(size 0.906272 0.906272)
			(drill 0.499872)
			(layers "*.Cu" "*.Mask")
			(remove_unused_layers no)
			(net "GND")
			(clearance 0.0508)
			(thermal_gap 0.0508)
		)
		(pad "T7" thru_hole circle
			(at 13.199872 35.100006 180)
			(size 0.906272 0.906272)
			(drill 0.499872)
			(layers "*.Cu" "*.Mask")
			(remove_unused_layers no)
			(net "GND")
			(clearance 0.0508)
			(thermal_gap 0.0508)
		)
		(pad "T9" thru_hole circle
			(at 17.599914 35.100006 180)
			(size 0.906272 0.906272)
			(drill 0.499872)
			(layers "*.Cu" "*.Mask")
			(remove_unused_layers no)
			(net "GND")
			(clearance 0.0508)
			(thermal_gap 0.0508)
		)
		(pad "T10" thru_hole circle
			(at 19.800062 35.299904 180)
			(size 0.71628 0.71628)
			(drill 0.30988)
			(layers "*.Cu" "*.Mask")
			(remove_unused_layers no)
			(net "Net_8853")
			(clearance 0.0508)
			(thermal_gap 0.0508)
		)
		(pad "U9" thru_hole circle
			(at 17.599914 36.399978 180)
			(size 0.71628 0.71628)
			(drill 0.30988)
			(layers "*.Cu" "*.Mask")
			(remove_unused_layers no)
			(net "Net_8851")
			(clearance 0.0508)
			(thermal_gap 0.0508)
		)
		(pad "U10" thru_hole circle
			(at 19.800062 36.599876 180)
			(size 0.71628 0.71628)
			(drill 0.30988)
			(layers "*.Cu" "*.Mask")
			(remove_unused_layers no)
			(net "Net_8852")
			(clearance 0.0508)
			(thermal_gap 0.0508)
		)
		(pad "V2" thru_hole circle
			(at 2.199894 37.900102 180)
			(size 0.906272 0.906272)
			(drill 0.499872)
			(layers "*.Cu" "*.Mask")
			(remove_unused_layers no)
			(net "GND")
			(clearance 0.0508)
			(thermal_gap 0.0508)
		)
		(pad "V4" thru_hole circle
			(at 6.599936 37.900102 180)
			(size 0.906272 0.906272)
			(drill 0.499872)
			(layers "*.Cu" "*.Mask")
			(remove_unused_layers no)
			(net "GND")
			(clearance 0.0508)
			(thermal_gap 0.0508)
		)
		(pad "V6" thru_hole circle
			(at 10.999978 37.900102 180)
			(size 0.906272 0.906272)
			(drill 0.499872)
			(layers "*.Cu" "*.Mask")
			(remove_unused_layers no)
			(net "GND")
			(clearance 0.0508)
			(thermal_gap 0.0508)
		)
		(pad "V8" thru_hole circle
			(at 15.40002 37.900102 180)
			(size 0.906272 0.906272)
			(drill 0.499872)
			(layers "*.Cu" "*.Mask")
			(remove_unused_layers no)
			(net "GND")
			(clearance 0.0508)
			(thermal_gap 0.0508)
		)
		(pad "V9" thru_hole circle
			(at 17.599914 37.69995 180)
			(size 0.71628 0.71628)
			(drill 0.30988)
			(layers "*.Cu" "*.Mask")
			(remove_unused_layers no)
			(net "Net_8850")
			(clearance 0.0508)
			(thermal_gap 0.0508)
		)
		(pad "V10" thru_hole circle
			(at 19.800062 37.900102 180)
			(size 0.906272 0.906272)
			(drill 0.499872)
			(layers "*.Cu" "*.Mask")
			(remove_unused_layers no)
			(net "GND")
			(clearance 0.0508)
			(thermal_gap 0.0508)
		)
		(pad "W1" thru_hole circle
			(at 0 38.999922 180)
			(size 0.906272 0.906272)
			(drill 0.499872)
			(layers "*.Cu" "*.Mask")
			(remove_unused_layers no)
			(net "GND")
			(clearance 0.0508)
			(thermal_gap 0.0508)
		)
		(pad "W3" thru_hole circle
			(at 4.400042 38.999922 180)
			(size 0.906272 0.906272)
			(drill 0.499872)
			(layers "*.Cu" "*.Mask")
			(remove_unused_layers no)
			(net "GND")
			(clearance 0.0508)
			(thermal_gap 0.0508)
		)
		(pad "W5" thru_hole circle
			(at 8.800084 38.999922 180)
			(size 0.906272 0.906272)
			(drill 0.499872)
			(layers "*.Cu" "*.Mask")
			(remove_unused_layers no)
			(net "GND")
			(clearance 0.0508)
			(thermal_gap 0.0508)
		)
		(pad "W7" thru_hole circle
			(at 13.199872 38.999922 180)
			(size 0.906272 0.906272)
			(drill 0.499872)
			(layers "*.Cu" "*.Mask")
			(remove_unused_layers no)
			(net "GND")
			(clearance 0.0508)
			(thermal_gap 0.0508)
		)
		(pad "W9" thru_hole circle
			(at 17.599914 38.999922 180)
			(size 0.906272 0.906272)
			(drill 0.499872)
			(layers "*.Cu" "*.Mask")
			(remove_unused_layers no)
			(net "GND")
			(clearance 0.0508)
			(thermal_gap 0.0508)
		)
		(pad "W10" thru_hole circle
			(at 19.800062 39.200074 180)
			(size 0.71628 0.71628)
			(drill 0.30988)
			(layers "*.Cu" "*.Mask")
			(remove_unused_layers no)
			(net "Net_8849")
			(clearance 0.0508)
			(thermal_gap 0.0508)
		)
		(pad "X9" thru_hole circle
			(at 17.599914 40.299894 180)
			(size 0.71628 0.71628)
			(drill 0.30988)
			(layers "*.Cu" "*.Mask")
			(remove_unused_layers no)
			(net "Net_8847")
			(clearance 0.0508)
			(thermal_gap 0.0508)
		)
		(pad "X10" thru_hole circle
			(at 19.800062 40.500046 180)
			(size 0.71628 0.71628)
			(drill 0.30988)
			(layers "*.Cu" "*.Mask")
			(remove_unused_layers no)
			(net "Net_8848")
			(clearance 0.0508)
			(thermal_gap 0.0508)
		)
		(pad "Y2" thru_hole circle
			(at 2.199894 41.800018 180)
			(size 0.906272 0.906272)
			(drill 0.499872)
			(layers "*.Cu" "*.Mask")
			(remove_unused_layers no)
			(net "GND")
			(clearance 0.0508)
			(thermal_gap 0.0508)
		)
		(pad "Y4" thru_hole circle
			(at 6.599936 41.800018 180)
			(size 0.906272 0.906272)
			(drill 0.499872)
			(layers "*.Cu" "*.Mask")
			(remove_unused_layers no)
			(net "GND")
			(clearance 0.0508)
			(thermal_gap 0.0508)
		)
		(pad "Y6" thru_hole circle
			(at 10.999978 41.800018 180)
			(size 0.906272 0.906272)
			(drill 0.499872)
			(layers "*.Cu" "*.Mask")
			(remove_unused_layers no)
			(net "GND")
			(clearance 0.0508)
			(thermal_gap 0.0508)
		)
		(pad "Y8" thru_hole circle
			(at 15.40002 41.800018 180)
			(size 0.906272 0.906272)
			(drill 0.499872)
			(layers "*.Cu" "*.Mask")
			(remove_unused_layers no)
			(net "GND")
			(clearance 0.0508)
			(thermal_gap 0.0508)
		)
		(pad "Y9" thru_hole circle
			(at 17.599914 41.60012 180)
			(size 0.71628 0.71628)
			(drill 0.30988)
			(layers "*.Cu" "*.Mask")
			(remove_unused_layers no)
			(net "Net_8846")
			(clearance 0.0508)
			(thermal_gap 0.0508)
		)
		(pad "Y10" thru_hole circle
			(at 19.800062 41.800018 180)
			(size 0.906272 0.906272)
			(drill 0.499872)
			(layers "*.Cu" "*.Mask")
			(remove_unused_layers no)
			(net "GND")
			(clearance 0.0508)
			(thermal_gap 0.0508)
		)
		(pad "Z1" thru_hole circle
			(at 0 42.900092 180)
			(size 0.906272 0.906272)
			(drill 0.499872)
			(layers "*.Cu" "*.Mask")
			(remove_unused_layers no)
			(net "GND")
			(clearance 0.0508)
			(thermal_gap 0.0508)
		)
		(pad "Z2" thru_hole circle
			(at 2.199894 43.09999 180)
			(size 0.71628 0.71628)
			(drill 0.30988)
			(layers "*.Cu" "*.Mask")
			(remove_unused_layers no)
			(net "MB_SWB_PWR_EN")
			(clearance 0.0508)
			(thermal_gap 0.0508)
		)
		(pad "Z3" thru_hole circle
			(at 4.400042 42.900092 180)
			(size 0.906272 0.906272)
			(drill 0.499872)
			(layers "*.Cu" "*.Mask")
			(remove_unused_layers no)
			(net "GND")
			(clearance 0.0508)
			(thermal_gap 0.0508)
		)
		(pad "Z4" thru_hole circle
			(at 6.599936 43.09999 180)
			(size 0.71628 0.71628)
			(drill 0.30988)
			(layers "*.Cu" "*.Mask")
			(remove_unused_layers no)
			(net "MB_BIC_READY_BUF_R_N")
			(clearance 0.0508)
			(thermal_gap 0.0508)
		)
		(pad "Z5" thru_hole circle
			(at 8.800084 42.900092 180)
			(size 0.906272 0.906272)
			(drill 0.499872)
			(layers "*.Cu" "*.Mask")
			(remove_unused_layers no)
			(net "GND")
			(clearance 0.0508)
			(thermal_gap 0.0508)
		)
		(pad "Z6" thru_hole circle
			(at 10.999978 43.09999 180)
			(size 0.71628 0.71628)
			(drill 0.30988)
			(layers "*.Cu" "*.Mask")
			(remove_unused_layers no)
			(net "RST_MB_BIC_N")
			(clearance 0.0508)
			(thermal_gap 0.0508)
		)
		(pad "Z7" thru_hole circle
			(at 13.199872 42.900092 180)
			(size 0.906272 0.906272)
			(drill 0.499872)
			(layers "*.Cu" "*.Mask")
			(remove_unused_layers no)
			(net "GND")
			(clearance 0.0508)
			(thermal_gap 0.0508)
		)
		(pad "Z8" thru_hole circle
			(at 15.40002 43.09999 180)
			(size 0.71628 0.71628)
			(drill 0.30988)
			(layers "*.Cu" "*.Mask")
			(remove_unused_layers no)
			(net "RST_MB_BMC_BUF_R_N")
			(clearance 0.0508)
			(thermal_gap 0.0508)
		)
		(pad "Z9" thru_hole circle
			(at 17.599914 42.900092 180)
			(size 0.906272 0.906272)
			(drill 0.499872)
			(layers "*.Cu" "*.Mask")
			(remove_unused_layers no)
			(net "GND")
			(clearance 0.0508)
			(thermal_gap 0.0508)
		)
		(pad "Z10" thru_hole circle
			(at 19.800062 43.09999 180)
			(size 0.71628 0.71628)
			(drill 0.30988)
			(layers "*.Cu" "*.Mask")
			(remove_unused_layers no)
			(net "UART_MB_BIC_RX")
			(clearance 0.0508)
			(thermal_gap 0.0508)
		)
	)
)
